(kicad_pcb
	(version 20260206)
	(generator "pcbnew")
	(generator_version "10.0")
	(general
		(thickness 1.21888)
		(legacy_teardrops no)
	)
	(paper "A4")
	(title_block
		(title "timecard-v8 — TimeCard-DC-V8_EXP.PcbDoc")
		(comment 1 "Time Appliance Project (Time Card) / footprints 114-119 of 288")
	)
	(layers
		(0 "F.Cu" signal "TOP")
		(4 "In1.Cu" signal "SGND")
		(6 "In2.Cu" signal "IN1")
		(8 "In3.Cu" signal "IN2")
		(10 "In4.Cu" signal "SGND1")
		(2 "B.Cu" signal "BOTTOM")
		(9 "F.Adhes" user "F.Adhesive")
		(11 "B.Adhes" user "B.Adhesive")
		(13 "F.Paste" user "Top Paste")
		(15 "B.Paste" user "Bottom Paste")
		(5 "F.SilkS" user "Top Overlay")
		(7 "B.SilkS" user "Bottom Overlay")
		(1 "F.Mask" user "Top Solder")
		(3 "B.Mask" user "Bottom Solder")
		(17 "Dwgs.User" user "User.Drawings")
		(19 "Cmts.User" user "User.Comments")
		(21 "Eco1.User" user "User.Eco1")
		(23 "Eco2.User" user "User.Eco2")
		(25 "Edge.Cuts" user)
		(27 "Margin" user)
		(31 "F.CrtYd" user "Top Courtyard")
		(29 "B.CrtYd" user "Bottom Courtyard")
		(35 "F.Fab" user "Top Component Center")
		(33 "B.Fab" user "Bottom Component Center")
	)
	(footprint "Vault:FP-0603-L_1_6_0_2-W_0_8_0-MFG"
		(layer "F.Cu")
		(at 228.3261 112.2162 -90)
		(property "Reference" "C22"
			(at 1.5 0.393345 270)
			(unlocked yes)
			(layer "F.SilkS")
			(effects
				(font
					(size 0.762 0.762)
					(thickness 0.2286)
				)
				(justify left bottom)
			)
		)
		(property "Value" "10uF_16V_0603"
			(at 4.193045 -22.9043 0)
			(unlocked yes)
			(layer "F.SilkS")
			(hide yes)
			(effects
				(font
					(size 0.762 0.762)
					(thickness 0.2286)
				)
				(justify left bottom)
			)
		)
		(sheetname "POWER")
		(sheetfile "POWER.kicad_sch")
		(duplicate_pad_numbers_are_jumpers no)
		(fp_line
			(start 0.9 0.825)
			(end -0.9 0.825)
			(stroke
				(width 0.2)
				(type solid)
			)
			(layer "F.SilkS")
		)
		(fp_line
			(start 0.9 -0.825)
			(end -0.9 -0.825)
			(stroke
				(width 0.2)
				(type solid)
			)
			(layer "F.SilkS")
		)
		(fp_line
			(start -1.15 0.6)
			(end -1.15 -0.6)
			(stroke
				(width 0.2)
				(type solid)
			)
			(layer "F.CrtYd")
		)
		(fp_line
			(start 1.15 0.6)
			(end -1.15 0.6)
			(stroke
				(width 0.2)
				(type solid)
			)
			(layer "F.CrtYd")
		)
		(fp_line
			(start 1.15 0.6)
			(end 1.15 -0.6)
			(stroke
				(width 0.2)
				(type solid)
			)
			(layer "F.CrtYd")
		)
		(fp_line
			(start 1.15 -0.6)
			(end -1.15 -0.6)
			(stroke
				(width 0.2)
				(type solid)
			)
			(layer "F.CrtYd")
		)
		(fp_line
			(start -1.15 0.6)
			(end -1.15 -0.6)
			(stroke
				(width 0.2)
				(type solid)
			)
			(layer "F.Fab")
		)
		(fp_line
			(start 1.15 0.6)
			(end -1.15 0.6)
			(stroke
				(width 0.2)
				(type solid)
			)
			(layer "F.Fab")
		)
		(fp_line
			(start 1.15 0.6)
			(end 1.15 -0.6)
			(stroke
				(width 0.2)
				(type solid)
			)
			(layer "F.Fab")
		)
		(fp_line
			(start 0 0.5)
			(end 0 -0.5)
			(stroke
				(width 0.1)
				(type solid)
			)
			(layer "F.Fab")
		)
		(fp_line
			(start 0.5 0)
			(end -0.5 0)
			(stroke
				(width 0.1)
				(type solid)
			)
			(layer "F.Fab")
		)
		(fp_line
			(start 1.15 -0.6)
			(end -1.15 -0.6)
			(stroke
				(width 0.2)
				(type solid)
			)
			(layer "F.Fab")
		)
		(fp_text user "${REFERENCE}"
			(at -0.00001 0.09602 270)
			(unlocked yes)
			(layer "F.Fab")
			(effects
				(font
					(face "Arial")
					(size 0.63 0.63)
					(thickness 0.1)
				)
				(justify left bottom)
			)
		)
		(pad "1" smd rect
			(at -0.7 0 270)
			(size 0.7 0.7)
			(layers "F.Cu" "F.Mask" "F.Paste")
			(net "+3.3V")
			(solder_mask_margin 0)
			(solder_paste_margin 0)
		)
		(pad "2" smd rect
			(at 0.7 0 270)
			(size 0.7 0.7)
			(layers "F.Cu" "F.Mask" "F.Paste")
			(net "GND")
			(solder_mask_margin 0)
			(solder_paste_margin 0)
		)
	)
	(footprint "Vault:RESC1608X55X30NL15T15"
		(layer "F.Cu")
		(at 84.1261 98.8662 -90)
		(property "Reference" "R14"
			(at 2.7714 -0.026931 90)
			(unlocked yes)
			(layer "F.SilkS")
			(effects
				(font
					(size 0.762 0.762)
					(thickness 0.2286)
				)
			)
		)
		(property "Value" "4.7K"
			(at 2.808471 -4.71014 0)
			(unlocked yes)
			(layer "F.SilkS")
			(hide yes)
			(effects
				(font
					(size 0.762 0.762)
					(thickness 0.2286)
				)
			)
		)
		(sheetname "USER_IO")
		(sheetfile "USER_IO.kicad_sch")
		(duplicate_pad_numbers_are_jumpers no)
		(pad "1" smd rect
			(at -0.75 0)
			(size 0.95 0.95)
			(layers "F.Cu" "F.Mask" "F.Paste")
			(net "ANT1_IO_OUT")
		)
		(pad "2" smd rect
			(at 0.75 0)
			(size 0.95 0.95)
			(layers "F.Cu" "F.Mask" "F.Paste")
			(net "+3.3V")
		)
	)
	(footprint "SamacSys:SOP50P310X90-8N"
		(layer "F.Cu")
		(at 82.1261 95.6162 180)
		(property "Reference" "U8"
			(at 0.228605 2.026931 180)
			(unlocked yes)
			(layer "F.SilkS")
			(effects
				(font
					(size 0.762 0.762)
					(thickness 0.2286)
				)
			)
		)
		(property "Value" "NC7WV125K8X"
			(at 6.207715 2.884671 180)
			(unlocked yes)
			(layer "F.SilkS")
			(hide yes)
			(effects
				(font
					(size 0.762 0.762)
					(thickness 0.2286)
				)
			)
		)
		(sheetname "USER_IO")
		(sheetfile "USER_IO.kicad_sch")
		(duplicate_pad_numbers_are_jumpers no)
		(fp_line
			(start 0.8 1)
			(end -0.8 1)
			(stroke
				(width 0.2)
				(type solid)
			)
			(layer "F.SilkS")
		)
		(fp_line
			(start 0.8 -1)
			(end 0.8 1)
			(stroke
				(width 0.2)
				(type solid)
			)
			(layer "F.SilkS")
		)
		(fp_line
			(start 0.8 -1)
			(end -0.8 -1)
			(stroke
				(width 0.2)
				(type solid)
			)
			(layer "F.SilkS")
		)
		(fp_line
			(start -0.8 -1)
			(end -0.8 1)
			(stroke
				(width 0.2)
				(type solid)
			)
			(layer "F.SilkS")
		)
		(fp_line
			(start -1.15 -1.25)
			(end -2 -1.25)
			(stroke
				(width 0.2)
				(type solid)
			)
			(layer "F.SilkS")
		)
		(pad "1" smd rect
			(at -1.575 -0.75 180)
			(size 0.85 0.3)
			(layers "F.Cu" "F.Mask" "F.Paste")
			(net "ANT1_IO_OUT")
		)
		(pad "2" smd rect
			(at -1.575 -0.25 180)
			(size 0.85 0.3)
			(layers "F.Cu" "F.Mask" "F.Paste")
			(net "ANT1_OUT")
		)
		(pad "3" smd rect
			(at -1.575 0.25 180)
			(size 0.85 0.3)
			(layers "F.Cu" "F.Mask" "F.Paste")
			(net "ANT1_IN")
		)
		(pad "4" smd rect
			(at -1.575 0.75 180)
			(size 0.85 0.3)
			(layers "F.Cu" "F.Mask" "F.Paste")
			(net "GND")
		)
		(pad "5" smd rect
			(at 1.575 0.75 180)
			(size 0.85 0.3)
			(layers "F.Cu" "F.Mask" "F.Paste")
			(net "NetR25_1")
		)
		(pad "6" smd rect
			(at 1.575 0.25 180)
			(size 0.85 0.3)
			(layers "F.Cu" "F.Mask" "F.Paste")
			(net "NetR25_1")
		)
		(pad "7" smd rect
			(at 1.575 -0.25 180)
			(size 0.85 0.3)
			(layers "F.Cu" "F.Mask" "F.Paste")
			(net "ANT1_IO_IN")
		)
		(pad "8" smd rect
			(at 1.575 -0.75 180)
			(size 0.85 0.3)
			(layers "F.Cu" "F.Mask" "F.Paste")
			(net "+3.3V")
		)
	)
	(footprint "Vault:FP-MK212BG-MFG"
		(layer "F.Cu")
		(at 233.2261 61.1162)
		(property "Reference" "C35"
			(at 2.6286 -1.173069 0)
			(unlocked yes)
			(layer "F.SilkS")
			(effects
				(font
					(size 0.762 0.762)
					(thickness 0.2286)
				)
			)
		)
		(property "Value" "10uF"
			(at -3.240281 2.22164 270)
			(unlocked yes)
			(layer "F.SilkS")
			(hide yes)
			(effects
				(font
					(size 0.762 0.762)
					(thickness 0.2286)
				)
			)
		)
		(sheetname "GPS_IMU_SENSORS")
		(sheetfile "GPS_IMU_SENSORS.kicad_sch")
		(duplicate_pad_numbers_are_jumpers no)
		(fp_line
			(start -0.125 -0.725)
			(end 0.125 -0.725)
			(stroke
				(width 0.2)
				(type solid)
			)
			(layer "F.SilkS")
		)
		(fp_line
			(start -0.125 0.725)
			(end 0.125 0.725)
			(stroke
				(width 0.2)
				(type solid)
			)
			(layer "F.SilkS")
		)
		(fp_line
			(start -1.6 -0.825)
			(end 1.6 -0.825)
			(stroke
				(width 0.2)
				(type solid)
			)
			(layer "F.CrtYd")
		)
		(fp_line
			(start -1.6 0.825)
			(end -1.6 -0.825)
			(stroke
				(width 0.2)
				(type solid)
			)
			(layer "F.CrtYd")
		)
		(fp_line
			(start -1.6 0.825)
			(end 1.6 0.825)
			(stroke
				(width 0.2)
				(type solid)
			)
			(layer "F.CrtYd")
		)
		(fp_line
			(start 1.6 0.825)
			(end 1.6 -0.825)
			(stroke
				(width 0.2)
				(type solid)
			)
			(layer "F.CrtYd")
		)
		(fp_line
			(start -1.6 -0.825)
			(end 1.6 -0.825)
			(stroke
				(width 0.2)
				(type solid)
			)
			(layer "F.Fab")
		)
		(fp_line
			(start -1.6 0.825)
			(end -1.6 -0.825)
			(stroke
				(width 0.2)
				(type solid)
			)
			(layer "F.Fab")
		)
		(fp_line
			(start -1.6 0.825)
			(end 1.6 0.825)
			(stroke
				(width 0.2)
				(type solid)
			)
			(layer "F.Fab")
		)
		(fp_line
			(start -0.5 0)
			(end 0.5 0)
			(stroke
				(width 0.1)
				(type solid)
			)
			(layer "F.Fab")
		)
		(fp_line
			(start 0 0.5)
			(end 0 -0.5)
			(stroke
				(width 0.1)
				(type solid)
			)
			(layer "F.Fab")
		)
		(fp_line
			(start 1.6 0.825)
			(end 1.6 -0.825)
			(stroke
				(width 0.2)
				(type solid)
			)
			(layer "F.Fab")
		)
		(fp_text user "${REFERENCE}"
			(at -0.00001 0.09602 360)
			(unlocked yes)
			(layer "F.Fab")
			(effects
				(font
					(face "Arial")
					(size 0.63 0.63)
					(thickness 0.1)
				)
				(justify left bottom)
			)
		)
		(pad "1" smd rect
			(at -1 0)
			(size 1 1.25)
			(layers "F.Cu" "F.Mask" "F.Paste")
			(net "+5.0V")
			(solder_mask_margin 0)
			(solder_paste_margin 0)
		)
		(pad "2" smd rect
			(at 1 0)
			(size 1 1.25)
			(layers "F.Cu" "F.Mask" "F.Paste")
			(net "GND")
			(solder_mask_margin 0)
			(solder_paste_margin 0)
		)
	)
	(footprint "Vault:TECO-1909763-1_V"
		(layer "F.Cu")
		(at 74.3761 95.1162 -90)
		(property "Reference" "J1"
			(at -2.723079 1.271395 0)
			(unlocked yes)
			(layer "F.SilkS")
			(effects
				(font
					(size 0.762 0.762)
					(thickness 0.2286)
				)
			)
		)
		(property "Value" "1909763-1"
			(at 4.582685 3.722871 270)
			(unlocked yes)
			(layer "F.SilkS")
			(hide yes)
			(effects
				(font
					(size 0.762 0.762)
					(thickness 0.2286)
				)
			)
		)
		(sheetname "USER_IO")
		(sheetfile "USER_IO.kicad_sch")
		(duplicate_pad_numbers_are_jumpers no)
		(fp_line
			(start 0.55 -1.3)
			(end -0.55 -1.3)
			(stroke
				(width 0.2)
				(type solid)
			)
			(layer "F.SilkS")
		)
		(fp_circle
			(center -1.778 1.65)
			(end -1.903 1.65)
			(stroke
				(width 0.25)
				(type solid)
			)
			(fill no)
			(layer "F.SilkS")
		)
		(pad "1" smd rect
			(at -1.475 0 270)
			(size 1.05 2.2)
			(layers "F.Cu" "F.Mask" "F.Paste")
			(net "GND")
		)
		(pad "2" smd rect
			(at 0 1.525 270)
			(size 1 1.05)
			(layers "F.Cu" "F.Mask" "F.Paste")
			(net "NetAN1_1")
		)
		(pad "3" smd rect
			(at 1.475 0 270)
			(size 1.05 2.2)
			(layers "F.Cu" "F.Mask" "F.Paste")
			(net "GND")
		)
	)
	(footprint "MIC24052YJL-TR:QFN28_5X6_MCH"
		(layer "F.Cu")
		(at 211.66439 109.33006 90)
		(property "Reference" "U1"
			(at 3.120515 1.76171 0)
			(unlocked yes)
			(layer "F.SilkS")
			(effects
				(font
					(size 0.762 0.762)
					(thickness 0.2286)
				)
				(justify left bottom)
			)
		)
		(property "Value" "MIC24052YJL-TR"
			(at -10.550285 4.81527 0)
			(unlocked yes)
			(layer "F.SilkS")
			(hide yes)
			(effects
				(font
					(size 0.762 0.762)
					(thickness 0.2286)
				)
				(justify left bottom)
			)
		)
		(sheetname "POWER")
		(sheetfile "POWER.kicad_sch")
		(duplicate_pad_numbers_are_jumpers no)
		(fp_line
			(start 2.9083 -3.4036)
			(end 2.9083 -2.56017)
			(stroke
				(width 0.1524)
				(type solid)
			)
			(layer "F.SilkS")
		)
		(fp_line
			(start 1.9205 -3.4036)
			(end 2.9083 -3.4036)
			(stroke
				(width 0.1524)
				(type solid)
			)
			(layer "F.SilkS")
		)
		(fp_line
			(start -2.9083 -3.4036)
			(end -1.92049 -3.4036)
			(stroke
				(width 0.1524)
				(type solid)
			)
			(layer "F.SilkS")
		)
		(fp_line
			(start -2.9083 -3.4036)
			(end -2.9083 -2.56017)
			(stroke
				(width 0.1524)
				(type solid)
			)
			(layer "F.SilkS")
		)
		(fp_line
			(start 2.9083 2.56018)
			(end 2.9083 3.4036)
			(stroke
				(width 0.1524)
				(type solid)
			)
			(layer "F.SilkS")
		)
		(fp_line
			(start -2.9083 2.56018)
			(end -2.9083 3.4036)
			(stroke
				(width 0.1524)
				(type solid)
			)
			(layer "F.SilkS")
		)
		(fp_line
			(start 1.9205 3.4036)
			(end 2.9083 3.4036)
			(stroke
				(width 0.1524)
				(type solid)
			)
			(layer "F.SilkS")
		)
		(fp_line
			(start -2.9083 3.4036)
			(end -1.92049 3.4036)
			(stroke
				(width 0.1524)
				(type solid)
			)
			(layer "F.SilkS")
		)
		(fp_text user "*"
			(at -3.5557 -2.190415 90)
			(unlocked yes)
			(layer "F.SilkS")
			(effects
				(font
					(size 1.27 1.27)
					(thickness 0.0762)
				)
				(justify left bottom)
			)
		)
		(pad "1" smd rect
			(at -2.4 -2.27499)
			(size 0.3 0.4)
			(layers "F.Cu" "F.Mask" "F.Paste")
			(net "P5V_PVDD")
			(solder_mask_margin 0)
			(solder_paste_margin -0.15)
		)
		(pad "2" smd rect
			(at -2.4 -1.625)
			(size 0.3 0.4)
			(layers "F.Cu" "F.Mask" "F.Paste")
			(net "GND")
			(solder_mask_margin 0)
			(solder_paste_margin -0.15)
		)
		(pad "3" smd rect
			(at -2.4 -0.97499)
			(size 0.3 0.4)
			(layers "F.Cu" "F.Mask" "F.Paste")
			(solder_mask_margin 0)
			(solder_paste_margin -0.15)
		)
		(pad "4" smd rect
			(at -2.4 -0.325)
			(size 0.3 0.4)
			(layers "F.Cu" "F.Mask" "F.Paste")
			(net "NetL1_1")
			(solder_mask_margin 0)
			(solder_paste_margin -0.15)
		)
		(pad "5" smd rect
			(at -2.4 0.32501)
			(size 0.3 0.4)
			(layers "F.Cu" "F.Mask" "F.Paste")
			(net "GND")
			(solder_mask_margin 0)
			(solder_paste_margin -0.15)
		)
		(pad "6" smd rect
			(at -2.4 0.975)
			(size 0.3 0.4)
			(layers "F.Cu" "F.Mask" "F.Paste")
			(net "GND")
			(solder_mask_margin 0)
			(solder_paste_margin -0.15)
		)
		(pad "7" smd rect
			(at -2.4 1.62501)
			(size 0.3 0.4)
			(layers "F.Cu" "F.Mask" "F.Paste")
			(net "GND")
			(solder_mask_margin 0)
			(solder_paste_margin -0.15)
		)
		(pad "8" smd rect
			(at -2.4 2.275)
			(size 0.3 0.4)
			(layers "F.Cu" "F.Mask" "F.Paste")
			(net "GND")
			(solder_mask_margin 0)
			(solder_paste_margin -0.15)
		)
		(pad "9" smd rect
			(at -1.625 2.9 270)
			(size 0.3 0.4)
			(layers "F.Cu" "F.Mask" "F.Paste")
			(net "NetL1_1")
			(solder_mask_margin 0)
			(solder_paste_margin -0.15)
		)
		(pad "10" smd rect
			(at -0.975 2.9 270)
			(size 0.3 0.4)
			(layers "F.Cu" "F.Mask" "F.Paste")
			(net "NetL1_1")
			(solder_mask_margin 0)
			(solder_paste_margin -0.15)
		)
		(pad "11" smd rect
			(at -0.325 2.9 270)
			(size 0.3 0.4)
			(layers "F.Cu" "F.Mask" "F.Paste")
			(net "NetL1_1")
			(solder_mask_margin 0)
			(solder_paste_margin -0.15)
		)
		(pad "12" smd rect
			(at 0.325 2.9 270)
			(size 0.3 0.4)
			(layers "F.Cu" "F.Mask" "F.Paste")
			(net "NetL1_1")
			(solder_mask_margin 0)
			(solder_paste_margin -0.15)
		)
		(pad "13" smd rect
			(at 0.975 2.9 270)
			(size 0.3 0.4)
			(layers "F.Cu" "F.Mask" "F.Paste")
			(net "+12V")
			(solder_mask_margin 0)
			(solder_paste_margin -0.15)
		)
		(pad "14" smd rect
			(at 1.625 2.9 270)
			(size 0.3 0.4)
			(layers "F.Cu" "F.Mask" "F.Paste")
			(net "+12V")
			(solder_mask_margin 0)
			(solder_paste_margin -0.15)
		)
		(pad "15" smd rect
			(at 2.4 2.275)
			(size 0.3 0.4)
			(layers "F.Cu" "F.Mask" "F.Paste")
			(net "+12V")
			(solder_mask_margin 0)
			(solder_paste_margin -0.15)
		)
		(pad "16" smd rect
			(at 2.4 1.62501)
			(size 0.3 0.4)
			(layers "F.Cu" "F.Mask" "F.Paste")
			(net "+12V")
			(solder_mask_margin 0)
			(solder_paste_margin -0.15)
		)
		(pad "17" smd rect
			(at 2.4 0.975)
			(size 0.3 0.4)
			(layers "F.Cu" "F.Mask" "F.Paste")
			(net "+12V")
			(solder_mask_margin 0)
			(solder_paste_margin -0.15)
		)
		(pad "18" smd rect
			(at 2.4 0.32501)
			(size 0.3 0.4)
			(layers "F.Cu" "F.Mask" "F.Paste")
			(net "+12V")
			(solder_mask_margin 0)
			(solder_paste_margin -0.15)
		)
		(pad "19" smd rect
			(at 2.4 -0.325)
			(size 0.3 0.4)
			(layers "F.Cu" "F.Mask" "F.Paste")
			(net "+12V")
			(solder_mask_margin 0)
			(solder_paste_margin -0.15)
		)
		(pad "20" smd rect
			(at 2.4 -0.97499)
			(size 0.3 0.4)
			(layers "F.Cu" "F.Mask" "F.Paste")
			(net "NetR4_1")
			(solder_mask_margin 0)
			(solder_paste_margin -0.15)
		)
		(pad "21" smd rect
			(at 2.4 -1.625)
			(size 0.3 0.4)
			(layers "F.Cu" "F.Mask" "F.Paste")
			(net "GND")
			(solder_mask_margin 0)
			(solder_paste_margin -0.15)
		)
		(pad "22" smd rect
			(at 2.4 -2.27499)
			(size 0.3 0.4)
			(layers "F.Cu" "F.Mask" "F.Paste")
			(net "NetC3_2")
			(solder_mask_margin 0)
			(solder_paste_margin -0.15)
		)
		(pad "23" smd rect
			(at 1.625 -2.89999 270)
			(size 0.3 0.4)
			(layers "F.Cu" "F.Mask" "F.Paste")
			(net "GND")
			(solder_mask_margin 0)
			(solder_paste_margin -0.15)
		)
		(pad "24" smd rect
			(at 0.975 -2.89999 270)
			(size 0.3 0.4)
			(layers "F.Cu" "F.Mask" "F.Paste")
			(net "P5V_FB")
			(solder_mask_margin 0)
			(solder_paste_margin -0.15)
		)
		(pad "25" smd rect
			(at 0.325 -2.89999 270)
			(size 0.3 0.4)
			(layers "F.Cu" "F.Mask" "F.Paste")
			(net "NetR3_2")
			(solder_mask_margin 0)
			(solder_paste_margin -0.15)
		)
		(pad "26" smd rect
			(at -0.325 -2.89999 270)
			(size 0.3 0.4)
			(layers "F.Cu" "F.Mask" "F.Paste")
			(net "NetR2_2")
			(solder_mask_margin 0)
			(solder_paste_margin -0.15)
		)
		(pad "27" smd rect
			(at -0.975 -2.89999 270)
			(size 0.3 0.4)
			(layers "F.Cu" "F.Mask" "F.Paste")
			(net "NetC6_1")
			(solder_mask_margin 0)
			(solder_paste_margin -0.15)
		)
		(pad "28" smd rect
			(at -1.625 -2.89999 270)
			(size 0.3 0.4)
			(layers "F.Cu" "F.Mask" "F.Paste")
			(net "P5V_VDD")
			(solder_mask_margin 0)
			(solder_paste_margin -0.15)
		)
		(pad "29" smd rect
			(at 0 -1.54999 90)
			(size 3.69999 1.6)
			(layers "F.Cu" "F.Mask" "F.Paste")
			(net "GND")
			(solder_mask_margin 0)
			(solder_paste_margin -0.8)
		)
		(pad "30" smd rect
			(at -0.5 1.015 90)
			(size 2.2 2.82999)
			(layers "F.Cu" "F.Mask" "F.Paste")
			(net "NetL1_1")
			(solder_mask_margin 0)
			(solder_paste_margin 0)
		)
		(pad "31" smd rect
			(at 1.4 1.015 90)
			(size 0.9 2.82999)
			(layers "F.Cu" "F.Mask" "F.Paste")
		)
	)
)
